# SCM (Grand Teton) — schematic netlist excerpt (pin names and nets, part order shuffled) for the footprints in the layout excerpt that follows; sources: Cadence DE-HDL packaged netlist, KiCad conversion of 12092022_DA0F0TMDCD0_F0T_Management_Board_D_brd_V3_OCP.brd

C191  Q_CAP  0.1UF 25V 10% X7R  pkg 0402  page 26 : A = P3V3_AUX ; B = GND
R318  Q_RES  0 5% CHIP  pkg 0402LF  page 35 : A = PWRGD_P3V3_AUX_R1 ; B = PWRGD_P3V3_AUX

(kicad_pcb
	(version 20260206)
	(generator "pcbnew")
	(generator_version "10.0")
	(general
		(thickness 1.6)
		(legacy_teardrops no)
	)
	(paper "A4")
	(title_block
		(title "12092022_DA0F0TMDCD0_F0T_Management_Board_D_brd_V3_OCP.brd")
		(comment 1 "Grand Teton / footprints 96-98 of 1440")
	)
	(layers
		(0 "F.Cu" signal "TOP")
		(4 "In1.Cu" signal "GND")
		(6 "In2.Cu" signal "IN1")
		(8 "In3.Cu" signal "GND1")
		(10 "In4.Cu" signal "IN2")
		(12 "In5.Cu" signal "VCC")
		(14 "In6.Cu" signal "VCC1")
		(16 "In7.Cu" signal "IN3")
		(18 "In8.Cu" signal "GND2")
		(20 "In9.Cu" signal "IN4")
		(22 "In10.Cu" signal "GND3")
		(2 "B.Cu" signal "BOTTOM")
		(9 "F.Adhes" user "F.Adhesive")
		(11 "B.Adhes" user "B.Adhesive")
		(13 "F.Paste" user "Package Geometry/Pastemask Top")
		(15 "B.Paste" user "Package Geometry/Pastemask Bottom")
		(5 "F.SilkS" user "Ref Des/Silkscreen Top")
		(7 "B.SilkS" user "Ref Des/Silkscreen Bottom")
		(1 "F.Mask" user "Board Geometry/Soldermask Top")
		(3 "B.Mask" user "Board Geometry/Soldermask Bottom")
		(17 "Dwgs.User" user "User.Drawings")
		(19 "Cmts.User" user "User.Comments")
		(21 "Eco1.User" user "User.Eco1")
		(23 "Eco2.User" user "User.Eco2")
		(25 "Edge.Cuts" user "Board Geometry/Outline")
		(27 "Margin" user)
		(31 "F.CrtYd" user "Package Geometry/Place Bound Top")
		(29 "B.CrtYd" user "Package Geometry/Place Bound Bottom")
		(35 "F.Fab" user "Ref Des/Assembly Top")
		(33 "B.Fab" user "Ref Des/Assembly Bottom")
	)
	(footprint ""
		(layer "F.Cu")
		(at 12.4206 -100.1649 180)
		(property "Reference" "R318"
			(at 0 0 180)
			(layer "F.SilkS")
			(hide yes)
			(effects
				(font
					(size 1.27 1.27)
				)
			)
		)
		(property "Value" ""
			(at 0 0 180)
			(layer "F.Fab")
			(effects
				(font
					(size 1.27 1.27)
				)
			)
		)
		(duplicate_pad_numbers_are_jumpers no)
		(fp_line
			(start 0.7874 0.4064)
			(end -0.7874 0.4064)
			(stroke
				(width 0.1524)
				(type default)
			)
			(layer "F.SilkS")
		)
		(fp_line
			(start 0.7874 -0.4064)
			(end 0.7874 0.4064)
			(stroke
				(width 0.1524)
				(type default)
			)
			(layer "F.SilkS")
		)
		(fp_line
			(start -0.7874 0.4064)
			(end -0.7874 -0.4064)
			(stroke
				(width 0.1524)
				(type default)
			)
			(layer "F.SilkS")
		)
		(fp_line
			(start -0.7874 -0.4064)
			(end 0.7874 -0.4064)
			(stroke
				(width 0.1524)
				(type default)
			)
			(layer "F.SilkS")
		)
		(fp_line
			(start 0.67945 0.3048)
			(end 0.120396 0.3048)
			(stroke
				(width 0.1)
				(type default)
			)
			(layer "F.Fab")
		)
		(fp_line
			(start 0.67945 -0.3048)
			(end 0.67945 0.3048)
			(stroke
				(width 0.1)
				(type default)
			)
			(layer "F.Fab")
		)
		(fp_line
			(start 0.12065 -0.2794)
			(end 0.12065 -0.3048)
			(stroke
				(width 0.1)
				(type default)
			)
			(layer "F.Fab")
		)
		(fp_line
			(start 0.12065 -0.3048)
			(end 0.67945 -0.3048)
			(stroke
				(width 0.1)
				(type default)
			)
			(layer "F.Fab")
		)
		(fp_line
			(start 0.120396 0.3048)
			(end 0.120396 0.2794)
			(stroke
				(width 0.1)
				(type default)
			)
			(layer "F.Fab")
		)
		(fp_line
			(start 0.120396 0.2794)
			(end -0.12065 0.2794)
			(stroke
				(width 0.1)
				(type default)
			)
			(layer "F.Fab")
		)
		(fp_line
			(start -0.12065 0.3048)
			(end -0.67945 0.3048)
			(stroke
				(width 0.1)
				(type default)
			)
			(layer "F.Fab")
		)
		(fp_line
			(start -0.12065 0.2794)
			(end -0.12065 0.3048)
			(stroke
				(width 0.1)
				(type default)
			)
			(layer "F.Fab")
		)
		(fp_line
			(start -0.12065 -0.2794)
			(end 0.12065 -0.2794)
			(stroke
				(width 0.1)
				(type default)
			)
			(layer "F.Fab")
		)
		(fp_line
			(start -0.12065 -0.305054)
			(end -0.12065 -0.2794)
			(stroke
				(width 0.1)
				(type default)
			)
			(layer "F.Fab")
		)
		(fp_line
			(start -0.67945 0.3048)
			(end -0.67945 -0.305054)
			(stroke
				(width 0.1)
				(type default)
			)
			(layer "F.Fab")
		)
		(fp_line
			(start -0.67945 -0.305054)
			(end -0.12065 -0.305054)
			(stroke
				(width 0.1)
				(type default)
			)
			(layer "F.Fab")
		)
		(pad "1" smd circle
			(at -0.40005 0 180)
			(size 0 0)
			(layers "F.Cu" "F.Mask" "F.Paste")
			(net "PWRGD_P3V3_AUX_R1")
		)
		(pad "2" smd circle
			(at 0.40005 0 180)
			(size 0 0)
			(layers "F.Cu" "F.Mask" "F.Paste")
			(net "PWRGD_P3V3_AUX")
		)
	)
	(footprint ""
		(layer "F.Cu")
		(at 13.262864 -9.779 180)
		(property "Reference" "C191"
			(at 0 0 180)
			(layer "F.SilkS")
			(hide yes)
			(effects
				(font
					(size 1.27 1.27)
				)
			)
		)
		(property "Value" ""
			(at 0 0 180)
			(layer "F.Fab")
			(effects
				(font
					(size 1.27 1.27)
				)
			)
		)
		(duplicate_pad_numbers_are_jumpers no)
		(fp_line
			(start 0.7874 0.4064)
			(end -0.7874 0.4064)
			(stroke
				(width 0.1524)
				(type default)
			)
			(layer "F.SilkS")
		)
		(fp_line
			(start 0.7874 -0.4064)
			(end 0.7874 0.4064)
			(stroke
				(width 0.1524)
				(type default)
			)
			(layer "F.SilkS")
		)
		(fp_line
			(start -0.7874 0.4064)
			(end -0.7874 -0.4064)
			(stroke
				(width 0.1524)
				(type default)
			)
			(layer "F.SilkS")
		)
		(fp_line
			(start -0.7874 -0.4064)
			(end 0.7874 -0.4064)
			(stroke
				(width 0.1524)
				(type default)
			)
			(layer "F.SilkS")
		)
		(fp_line
			(start 0.67945 0.3048)
			(end 0.120396 0.3048)
			(stroke
				(width 0.1)
				(type default)
			)
			(layer "F.Fab")
		)
		(fp_line
			(start 0.67945 -0.3048)
			(end 0.67945 0.3048)
			(stroke
				(width 0.1)
				(type default)
			)
			(layer "F.Fab")
		)
		(fp_line
			(start 0.12065 -0.2794)
			(end 0.12065 -0.3048)
			(stroke
				(width 0.1)
				(type default)
			)
			(layer "F.Fab")
		)
		(fp_line
			(start 0.12065 -0.3048)
			(end 0.67945 -0.3048)
			(stroke
				(width 0.1)
				(type default)
			)
			(layer "F.Fab")
		)
		(fp_line
			(start 0.120396 0.3048)
			(end 0.120396 0.2794)
			(stroke
				(width 0.1)
				(type default)
			)
			(layer "F.Fab")
		)
		(fp_line
			(start 0.120396 0.2794)
			(end -0.12065 0.2794)
			(stroke
				(width 0.1)
				(type default)
			)
			(layer "F.Fab")
		)
		(fp_line
			(start -0.12065 0.3048)
			(end -0.67945 0.3048)
			(stroke
				(width 0.1)
				(type default)
			)
			(layer "F.Fab")
		)
		(fp_line
			(start -0.12065 0.2794)
			(end -0.12065 0.3048)
			(stroke
				(width 0.1)
				(type default)
			)
			(layer "F.Fab")
		)
		(fp_line
			(start -0.12065 -0.2794)
			(end 0.12065 -0.2794)
			(stroke
				(width 0.1)
				(type default)
			)
			(layer "F.Fab")
		)
		(fp_line
			(start -0.12065 -0.305054)
			(end -0.12065 -0.2794)
			(stroke
				(width 0.1)
				(type default)
			)
			(layer "F.Fab")
		)
		(fp_line
			(start -0.67945 0.3048)
			(end -0.67945 -0.305054)
			(stroke
				(width 0.1)
				(type default)
			)
			(layer "F.Fab")
		)
		(fp_line
			(start -0.67945 -0.305054)
			(end -0.12065 -0.305054)
			(stroke
				(width 0.1)
				(type default)
			)
			(layer "F.Fab")
		)
		(pad "1" smd circle
			(at -0.40005 0 180)
			(size 0 0)
			(layers "F.Cu" "F.Mask" "F.Paste")
			(net "P3V3_AUX")
		)
		(pad "2" smd circle
			(at 0.40005 0 180)
			(size 0 0)
			(layers "F.Cu" "F.Mask" "F.Paste")
			(net "GND")
		)
	)
	(footprint ""
		(layer "F.Cu")
		(at 2.65938 -18.161)
		(property "Reference" ""
			(at 0 0 0)
			(layer "F.SilkS")
			(hide yes)
			(effects
				(font
					(size 1.27 1.27)
				)
			)
		)
		(property "Value" ""
			(at 0 0 0)
			(layer "F.Fab")
			(effects
				(font
					(size 1.27 1.27)
				)
			)
		)
		(duplicate_pad_numbers_are_jumpers no)
		(pad "1" smd circle
			(at 0 0)
			(size 0.9906 0.9906)
			(layers "F.Cu" "F.Mask" "F.Paste")
			(net "Net_596")
		)
		(zone
			(layer "F.Cu")
			(hatch none 0.5)
			(connect_pads
				(clearance 0)
			)
			(min_thickness 0.25)
			(keepout
				(tracks not_allowed)
				(vias allowed)
				(pads allowed)
				(copperpour not_allowed)
				(footprints allowed)
			)
			(placement
				(enabled no)
				(sheetname "")
			)
			(fill
				(thermal_gap 0.5)
				(thermal_bridge_width 0.5)
				(island_removal_mode 0)
			)
			(polygon
				(pts
					(arc
						(start 4.28498 -18.161)
						(mid 1.03378 -18.161)
						(end 4.28498 -18.161)
					)
				)
			)
		)
	)
)
